# BASEBOARD_FAB2 (Tioga Pass) — schematic netlist excerpt (pin names and nets, part order shuffled) for the footprints in the layout excerpt that follows; sources: Cadence DE-HDL packaged netlist, KiCad conversion of Wiwynn_Tioga_Pass_MB.brd

C8P22  CAP  100UF 4V 20% X5R  pkg 0805  page 76 : A = PVCCMCP_CPU1 ; B = GND
C1L8  CAP_A  0.1UF 16V 10% X7R  pkg 0402V  page 111 : A = XDP_PWRGD_RST_N ; B = GND
C2T34  CAP_A  0.1UF 16V 10% X7R  pkg 0402V  page 101 : A = P3V3_STBY_MNG ; B = GND

(kicad_pcb
	(version 20260206)
	(generator "pcbnew")
	(generator_version "10.0")
	(general
		(thickness 1.6)
		(legacy_teardrops no)
	)
	(paper "A4")
	(title_block
		(title "Wiwynn_Tioga_Pass_MB.brd")
		(comment 1 "Tioga Pass / footprints 3667-3669 of 4770")
	)
	(layers
		(0 "F.Cu" signal "TOP")
		(4 "In1.Cu" signal "L2GND")
		(6 "In2.Cu" signal "L3")
		(8 "In3.Cu" signal "L4GND")
		(10 "In4.Cu" signal "L5")
		(12 "In5.Cu" signal "L6GND")
		(14 "In6.Cu" signal "L7VCC")
		(16 "In7.Cu" signal "L8VCC")
		(18 "In8.Cu" signal "L9GND")
		(20 "In9.Cu" signal "L10")
		(22 "In10.Cu" signal "L11GND")
		(24 "In11.Cu" signal "L12")
		(26 "In12.Cu" signal "L13GND")
		(2 "B.Cu" signal "BOTTOM")
		(9 "F.Adhes" user "F.Adhesive")
		(11 "B.Adhes" user "B.Adhesive")
		(13 "F.Paste" user "Package Geometry/Pastemask Top")
		(15 "B.Paste" user "Package Geometry/Pastemask Bottom")
		(5 "F.SilkS" user "Ref Des/Silkscreen Top")
		(7 "B.SilkS" user "Ref Des/Silkscreen Bottom")
		(1 "F.Mask" user "Board Geometry/Soldermask Top")
		(3 "B.Mask" user "Board Geometry/Soldermask Bottom")
		(17 "Dwgs.User" user "User.Drawings")
		(19 "Cmts.User" user "User.Comments")
		(21 "Eco1.User" user "User.Eco1")
		(23 "Eco2.User" user "User.Eco2")
		(25 "Edge.Cuts" user "Board Geometry/Outline")
		(27 "Margin" user)
		(31 "F.CrtYd" user "Package Geometry/Place Bound Top")
		(29 "B.CrtYd" user "Package Geometry/Place Bound Bottom")
		(35 "F.Fab" user "Ref Des/Assembly Top")
		(33 "B.Fab" user "Ref Des/Assembly Bottom")
	)
	(footprint ""
		(layer "B.Cu")
		(at 106.350054 -73.51014)
		(property "Reference" "C8P22"
			(at 0 0 0)
			(layer "B.SilkS")
			(hide yes)
			(effects
				(font
					(size 1.27 1.27)
				)
				(justify mirror)
			)
		)
		(property "Value" ""
			(at 0 0 0)
			(layer "B.Fab")
			(effects
				(font
					(size 1.27 1.27)
				)
				(justify mirror)
			)
		)
		(duplicate_pad_numbers_are_jumpers no)
		(fp_poly
			(pts
				(xy 0.7239 -0.2159) (xy -0.7239 -0.2159) (xy -0.7239 1.9939) (xy 0.7239 1.9939)
			)
			(stroke
				(width 0)
				(type default)
			)
			(fill no)
			(layer "B.CrtYd")
		)
		(fp_line
			(start -0.7239 -0.2159)
			(end 0.7239 -0.2159)
			(stroke
				(width 0.1)
				(type default)
			)
			(layer "B.Fab")
		)
		(fp_line
			(start -0.7239 1.9939)
			(end -0.7239 -0.2159)
			(stroke
				(width 0.1)
				(type default)
			)
			(layer "B.Fab")
		)
		(fp_line
			(start 0.7239 -0.2159)
			(end 0.7239 1.9939)
			(stroke
				(width 0.1)
				(type default)
			)
			(layer "B.Fab")
		)
		(fp_line
			(start 0.7239 1.9939)
			(end -0.7239 1.9939)
			(stroke
				(width 0.1)
				(type default)
			)
			(layer "B.Fab")
		)
		(pad "1" smd rect
			(at 0 0 180)
			(size 1.27 1.016)
			(layers "B.Cu" "B.Mask" "B.Paste")
			(net "PVCCMCP_CPU1")
		)
		(pad "2" smd rect
			(at 0 1.778 180)
			(size 1.27 1.016)
			(layers "B.Cu" "B.Mask" "B.Paste")
			(net "GND")
		)
		(zone
			(layer "B.Cu")
			(hatch none 0.5)
			(connect_pads
				(clearance 0)
			)
			(min_thickness 0.25)
			(keepout
				(tracks not_allowed)
				(vias allowed)
				(pads allowed)
				(copperpour not_allowed)
				(footprints allowed)
			)
			(placement
				(enabled no)
				(sheetname "")
			)
			(fill
				(thermal_gap 0.5)
				(thermal_bridge_width 0.5)
				(island_removal_mode 0)
			)
			(polygon
				(pts
					(xy 106.985054 -73.00214) (xy 105.715054 -73.00214) (xy 105.715054 -72.24014) (xy 106.985054 -72.24014)
				)
			)
		)
	)
	(footprint ""
		(layer "B.Cu")
		(at 463.690208 -145.415254)
		(property "Reference" "C1L8"
			(at 0 0 0)
			(layer "B.SilkS")
			(hide yes)
			(effects
				(font
					(size 1.27 1.27)
				)
				(justify mirror)
			)
		)
		(property "Value" ""
			(at 0 0 0)
			(layer "B.Fab")
			(effects
				(font
					(size 1.27 1.27)
				)
				(justify mirror)
			)
		)
		(duplicate_pad_numbers_are_jumpers no)
		(fp_poly
			(pts
				(xy -0.3048 -0.1016) (xy -0.3048 0.9906) (xy 0.3048 0.9906) (xy 0.3048 -0.1016)
			)
			(stroke
				(width 0)
				(type default)
			)
			(fill no)
			(layer "B.CrtYd")
		)
		(fp_line
			(start -0.3048 -0.1016)
			(end 0.3048 -0.1016)
			(stroke
				(width 0.1)
				(type default)
			)
			(layer "B.Fab")
		)
		(fp_line
			(start -0.3048 0.9906)
			(end -0.3048 -0.1016)
			(stroke
				(width 0.1)
				(type default)
			)
			(layer "B.Fab")
		)
		(fp_line
			(start 0.3048 -0.1016)
			(end 0.3048 0.9906)
			(stroke
				(width 0.1)
				(type default)
			)
			(layer "B.Fab")
		)
		(fp_line
			(start 0.3048 0.9906)
			(end -0.3048 0.9906)
			(stroke
				(width 0.1)
				(type default)
			)
			(layer "B.Fab")
		)
		(pad "1" smd rect
			(at 0 0 180)
			(size 0.508 0.508)
			(layers "B.Cu" "B.Mask" "B.Paste")
			(net "XDP_PWRGD_RST_N")
		)
		(pad "2" smd rect
			(at 0 0.889 180)
			(size 0.508 0.508)
			(layers "B.Cu" "B.Mask" "B.Paste")
			(net "GND")
		)
		(zone
			(layer "B.Cu")
			(hatch none 0.5)
			(connect_pads
				(clearance 0)
			)
			(min_thickness 0.25)
			(keepout
				(tracks allowed)
				(vias not_allowed)
				(pads allowed)
				(copperpour not_allowed)
				(footprints allowed)
			)
			(placement
				(enabled no)
				(sheetname "")
			)
			(fill
				(thermal_gap 0.5)
				(thermal_bridge_width 0.5)
				(island_removal_mode 0)
			)
			(polygon
				(pts
					(xy 463.944208 -145.161254) (xy 463.436208 -145.161254) (xy 463.436208 -144.780254) (xy 463.944208 -144.780254)
				)
			)
		)
		(zone
			(layer "B.Cu")
			(hatch none 0.5)
			(connect_pads
				(clearance 0)
			)
			(min_thickness 0.25)
			(keepout
				(tracks not_allowed)
				(vias allowed)
				(pads allowed)
				(copperpour not_allowed)
				(footprints allowed)
			)
			(placement
				(enabled no)
				(sheetname "")
			)
			(fill
				(thermal_gap 0.5)
				(thermal_bridge_width 0.5)
				(island_removal_mode 0)
			)
			(polygon
				(pts
					(xy 463.944208 -144.780254) (xy 463.436208 -144.780254) (xy 463.436208 -145.161254) (xy 463.944208 -145.161254)
				)
			)
		)
	)
	(footprint ""
		(layer "B.Cu")
		(at 479.8695 -33.147 -90)
		(property "Reference" "C2T34"
			(at 0 0 90)
			(layer "B.SilkS")
			(hide yes)
			(effects
				(font
					(size 1.27 1.27)
				)
				(justify mirror)
			)
		)
		(property "Value" ""
			(at 0 0 90)
			(layer "B.Fab")
			(effects
				(font
					(size 1.27 1.27)
				)
				(justify mirror)
			)
		)
		(duplicate_pad_numbers_are_jumpers no)
		(fp_poly
			(pts
				(xy -0.3048 -0.1016) (xy -0.3048 0.9906) (xy 0.3048 0.9906) (xy 0.3048 -0.1016)
			)
			(stroke
				(width 0)
				(type default)
			)
			(fill no)
			(layer "B.CrtYd")
		)
		(fp_line
			(start -0.3048 0.9906)
			(end -0.3048 -0.1016)
			(stroke
				(width 0.1)
				(type default)
			)
			(layer "B.Fab")
		)
		(fp_line
			(start 0.3048 0.9906)
			(end -0.3048 0.9906)
			(stroke
				(width 0.1)
				(type default)
			)
			(layer "B.Fab")
		)
		(fp_line
			(start -0.3048 -0.1016)
			(end 0.3048 -0.1016)
			(stroke
				(width 0.1)
				(type default)
			)
			(layer "B.Fab")
		)
		(fp_line
			(start 0.3048 -0.1016)
			(end 0.3048 0.9906)
			(stroke
				(width 0.1)
				(type default)
			)
			(layer "B.Fab")
		)
		(pad "1" smd rect
			(at 0 0 90)
			(size 0.508 0.508)
			(layers "B.Cu" "B.Mask" "B.Paste")
			(net "P3V3_STBY_MNG")
		)
		(pad "2" smd rect
			(at 0 0.889 90)
			(size 0.508 0.508)
			(layers "B.Cu" "B.Mask" "B.Paste")
			(net "GND")
		)
		(zone
			(layer "B.Cu")
			(hatch none 0.5)
			(connect_pads
				(clearance 0)
			)
			(min_thickness 0.25)
			(keepout
				(tracks not_allowed)
				(vias allowed)
				(pads allowed)
				(copperpour not_allowed)
				(footprints allowed)
			)
			(placement
				(enabled no)
				(sheetname "")
			)
			(fill
				(thermal_gap 0.5)
				(thermal_bridge_width 0.5)
				(island_removal_mode 0)
			)
			(polygon
				(pts
					(xy 479.2345 -32.893) (xy 479.2345 -33.401) (xy 479.6155 -33.401) (xy 479.6155 -32.893)
				)
			)
		)
		(zone
			(layer "B.Cu")
			(hatch none 0.5)
			(connect_pads
				(clearance 0)
			)
			(min_thickness 0.25)
			(keepout
				(tracks allowed)
				(vias not_allowed)
				(pads allowed)
				(copperpour not_allowed)
				(footprints allowed)
			)
			(placement
				(enabled no)
				(sheetname "")
			)
			(fill
				(thermal_gap 0.5)
				(thermal_bridge_width 0.5)
				(island_removal_mode 0)
			)
			(polygon
				(pts
					(xy 479.6155 -32.893) (xy 479.6155 -33.401) (xy 479.2345 -33.401) (xy 479.2345 -32.893)
				)
			)
		)
	)
)
